# T6G (Grand Teton) — schematic netlist excerpt (pin names and nets, part order shuffled) for the footprints in the layout excerpt that follows; sources: Cadence DE-HDL packaged netlist, KiCad conversion of 04192023_DAF0TMB3IC0_F0TG_MB_C_brd_V02_OCP.brd

J41  SCONN168_ME1016810202011  IO  pkg CON_F168S2H7D_P0-6W2-95_LUH  page 150
  GND_A1  = SMB_OCP_SFF_3V3AUX_SCL_R0
  GND_A2  = SMB_OCP_SFF_3V3AUX_SDA_R0
  GND_A3  = SMB_CPU0_CPU1_APML_SCL_R
  GND_A4  = SMB_CPU0_CPU1_APML_SDA_R
  GND_A5  = SMB_VR_3V3AUX_SCL_R0
  GND_A6  = SMB_VR_3V3AUX_SDA_R0
  SMCLK  = SMB_CPU0_CPU1_SEC_SCL_R
  SMDAT  = SMB_CPU0_CPU1_SEC_SDA_R
  \smrst#\  = I3C_BMC_SWB_SCL
  \prsnta#\  = I3C_BMC_SWB_SDA
  \perst1#\  = SMB_OCP_V3_2_3V3AUX_SCL_R0
  \prsntb2#\  = SMB_OCP_V3_2_3V3AUX_SDA_R0
  GND_A13  = GND
  REFCLKN1  = CLK_100M_CPU0_CLK01_DP
  REFCLKP1  = CLK_100M_CPU0_CLK01_DN
  GND_A16  = GND
  PERN0  = P2E_CPU0_P5_TX_C_DP
  PERP0  = P2E_CPU0_P5_TX_C_DN
  GND_A19  = GND
  PERN1  = P2E_CPU0_P5_RX_DP
  PERP1  = P2E_CPU0_P5_RX_DN
  GND_A22  = GND
  PERN2  = SMB_PCIE0_3V3AUX_SCL
  PERP2  = SMB_PCIE0_3V3AUX_SDA
  GND_A25  = SMB_PMBUS_3V3AUX_SCL_R0
  PERN3  = SMB_PMBUS_3V3AUX_SDA_R0
  PERP3  = SMB_1_PLD_3V3AUX_SCL_R3
  GND_A28  = SMB_1_PLD_3V3AUX_SDA_R3
  GND_A29  = SMB_FAN_3V3AUX_SCL
  PERN4  = SMB_FAN_3V3AUX_SDA
  PERP4  = SMB_PCIE2_3V3AUX_SCL_R0
  GND_A32  = SMB_PCIE2_3V3AUX_SDA_R0
  PERN5  = GND
  PERP5  = JTAG_SCM_TCK
  GND_A35  = JTAG_SCM_TMS
  PERN6  = JTAG_SCM_TDI_R
  PERP6  = JTAG_SCM_TDO_R
  GND_A38  = SMB_PCIE3_3V3AUX_SCL_R
  PERN7  = SMB_PCIE3_3V3AUX_SDA_R
  PERP7  = SMB_HOST_CLK_3V3AUX_SCL_R0
  GND_A41  = SMB_HOST_CLK_3V3AUX_SDA_R0
  \prsntb1#\  = GND
  GND_A43  = FW_RECOVERY
  PERN8  = PWRGD_PS_PWROK_R
  PERP8  = TP_STBY_EN
  GND_A46  = RST_MB_STBY_R_N
  PERN9  = SCM_SYS_PWRBTN_R_N
  PERP9  = SCM_SYS_PWROK_R1
  GND_A49  = SCM_HDT_DBREQ_N
  PERN10  = PU_JTAG_DBP_BMC_PRDY_N
  PERP10  = FM_RST_PERST_SCM_N
  GND_A52  = FM_UARTSW_MSB_R
  PERN11  = SCM_ROT_CPU_RST_N
  PERP11  = TP_CHASI
  GND_A55  = FM_UARTSW_LSB_R
  PERN12  = IRQ0_A56
  PERP12  = FM_SCM_PRSNT1_N
  GND_A58  = GND
  PERN13  = USB3_CPU0_BMC_RX_DP
  PERP13  = USB3_CPU0_BMC_RX_DN
  GND_A61  = GND
  PERN14  = TP_PCIE_RXP<1>
  PERP14  = TP_PCIE_RXN<1>
  GND_A64  = GND
  PERN15  = P2E_MB_BMC_RX_BUF_DP<0>
  PERP15  = P2E_MB_BMC_RX_BUF_DN<0>
  GND_A67  = GND
  USB_DATN  = CLK_100M_BMC_RC_DP
  USB_DATP  = CLK_100M_BMC_RC_DN
  \pwrbrk0#\  = GND
  \+12v_edge_b1\  = CLK_ESPI_CPU0_CLK1
  \+12v_edge_b2\  = ESPI_CPU0_CS1_N
  \+12v_edge_b3\  = ESPI_CPU0_ALERT_N
  \+12v_edge_b4\  = RST_ESPI_CPU0_RSTOUT_N
  \+12v_edge_b5\  = ESPI_CPU0_D0
  \+12v_edge_b6\  = ESPI_CPU0_D1
  \bif0#\  = ESPI_CPU0_D2
  \bif1#\  = ESPI_CPU0_D3
  \bif2#\  = FM_LPC_ESPI_SEL
  \perst0#\  = GND
  \+3.3v_edge\  = SPI_CPU0_LVC3_SCM_CLK
  AUX_PWR_EN  = SPI_CPU0_LVC3_SCM_CS0_N
  GND_B13  = SPI_CPU0_LVC3_SCM_D0
  REFCLKN0  = SPI_CPU0_LVC3_SCM_D1
  REFCLKP0  = SPI_CPU0_LVC3_SCM_D2
  GND_B16  = SPI_CPU0_LVC3_SCM_D3
  PETN0  = GND
  PETP0  = CLK_50M_RMII_BMC_OCP
  GND_B19  = RMII_OCP_BMC_CRSDV
  PETN1  = RMII_BMC_OCP_TX_EN
  PETP1  = RMII_BMC_OCP_TXD_0
  GND_B22  = RMII_BMC_OCP_TXD_1
  PETN2  = RMII_BMC_OCP_RX_ER
  PETP2  = RMII_OCP_BMC_RXD_0
  GND_B25  = RMII_OCP_BMC_RXD_1
  PETN3  = GND
  PETP3  = TP_PECI_BMC
  GND_B28  = TP_PVCCIO_PECI_BMC
  GND_B29  = SGPIO_SCM_DO_R_<0>
  PETN4  = SGPIO_SCM_CLK_R_<0>
  PETP4  = SGPIO_SCM_DI_R_<0>
  GND_B32  = SGPIO_SCM_LD_R_<0>
  PETN5  = GND
  PETP5  = SGPIO_SCM_DO_R_<1>
  GND_B35  = SGPIO_SCM_CLK_R_<1>
  PETN6  = SGPIO_SCM_DI_R_<1>
  PETP6  = SGPIO_SCM_LD_R_<1>
  GND_B38  = GND
  PETN7  = SGPIO_SCM_RESET_R_N
  PETP7  = SGPIO_SCM_INTR_R1_N
  GND_B41  = SCM_VDD_RTC
  \prsntb0#\  = FM_AC_PWR_BTN_N
  GND_B43  = TP_SPI_2_PLD_CLK
  PETN8  = TP_SPI_2_PLD_CS_N
  PETP8  = TP_SPI_2_PLD_IO0
  GND_B46  = TP_SPI_2_PLD_IO1
  PETN9  = TP_SPI_2_PLD_IO2
  PETP9  = TP_SPI_2_PLD_IO3
  GND_B49  = GND
  PETN10  = USB2_HOST_BMC_B_DP
  PETP10  = USB2_HOST_BMC_B_DN
  GND_B52  = GND
  PETN11  = USB2_CPU0_P1_DP
  PETP11  = USB2_CPU0_P1_DN
  GND_B55  = GND
  PETN12  = USB2_HUB_EXT_DP
  PETP12  = USB2_HUB_EXT_DN
  GND_B58  = GND
  PETN13  = USB3_CPU0_BMC_TX_BUF_C_DP
  PETP13  = USB3_CPU0_BMC_TX_BUF_C_DN
  GND_B61  = GND
  PETN14  = TP_PCIE_TXP<1>
  PETP14  = TP_PCIE_TXN<1>
  GND_B64  = GND
  PETN15  = P2E_MB_BMC_TX_C_DP<0>
  PETP15  = P2E_MB_BMC_TX_C_DN<0>
  GND_B67  = GND
  RFU1_NC_B68  = TP_PCIE_TXP<3>
  RFU1_NC_B69  = TP_BEEP_LED
  \prsntb3#\  = GND
  G1  = GND
  G2  = GND
  G3  = GND
  G4  = GND
  G5  = GND
  \perst2#\  = P12V_SCM
  \perst3#\  = P12V_SCM
  \wake#\  = GND
  RBT_ARB_IN  = GND
  RBT_ARB_OUT  = I3C_SCM_0_SCL
  SLOT_ID1  = I3C_SCM_0_SDA
  RBT_TX_EN  = I3C_SCM_1_SCL
  RBT_TXD1  = I3C_SCM_1_SDA
  RBT_TXD0  = I3C_SCM_2_SCL
  GND_OA10  = I3C_SCM_2_SDA
  REFCLKN3  = I3C_SCM_3_SCL
  REFCLKP3  = I3C_SCM_3_SDA
  GND_OA13  = GND
  RBT_CLK_IN  = VIRTUAL_RESEAT
  NIC_PWR_GOOD  = P12V_SCM
  MAIN_PWR_EN  = P12V_SCM
  \ld#\  = PRSNT0_N
  DATA_IN  = GND
  DATA_OUT  = UART_BMC_BIC_TX
  CLK  = UART_BMC_BIC_BUF_RX
  SLOT_ID0  = GND
  RBT_RXD1  = UART_CPU0_SCM_LVC3_UART1_RX
  RBT_RXD0  = UART_CPU0_SCM_LVC3_UART1_R1_TX
  GND_OB10  = GND
  REFCLKN2  = RST_SRST_PLD_BMC_N
  REFCLKP2  = SPI_CPU0_LVC3_TPM_CS_N
  GND_OB13  = FPGA_IO3V3_RSVD_1
  RBT_CRS_DV  = FM_SOL_UART_CH_SEL_R

(kicad_pcb
	(version 20260206)
	(generator "pcbnew")
	(generator_version "10.0")
	(general
		(thickness 1.6)
		(legacy_teardrops no)
	)
	(paper "A4")
	(title_block
		(title "04192023_DAF0TMB3IC0_F0TG_MB_C_brd_V02_OCP.brd")
		(comment 1 "Grand Teton / footprint 3166 of 8354 (J41), pads 43-87 of 175")
	)
	(layers
		(0 "F.Cu" signal "TOP")
		(4 "In1.Cu" signal "GND")
		(6 "In2.Cu" signal "IN1")
		(8 "In3.Cu" signal "GND1")
		(10 "In4.Cu" signal "IN2")
		(12 "In5.Cu" signal "GND2")
		(14 "In6.Cu" signal "IN3")
		(16 "In7.Cu" signal "GND3")
		(18 "In8.Cu" signal "VCC")
		(20 "In9.Cu" signal "VCC1")
		(22 "In10.Cu" signal "GND4")
		(24 "In11.Cu" signal "IN4")
		(26 "In12.Cu" signal "GND5")
		(28 "In13.Cu" signal "IN5")
		(30 "In14.Cu" signal "GND6")
		(32 "In15.Cu" signal "IN6")
		(34 "In16.Cu" signal "GND7")
		(2 "B.Cu" signal "BOTTOM")
		(9 "F.Adhes" user "F.Adhesive")
		(11 "B.Adhes" user "B.Adhesive")
		(13 "F.Paste" user "Package Geometry/Pastemask Top")
		(15 "B.Paste" user "Package Geometry/Pastemask Bottom")
		(5 "F.SilkS" user "Ref Des/Silkscreen Top")
		(7 "B.SilkS" user "Ref Des/Silkscreen Bottom")
		(1 "F.Mask" user "Board Geometry/Soldermask Top")
		(3 "B.Mask" user "Board Geometry/Soldermask Bottom")
		(17 "Dwgs.User" user "User.Drawings")
		(19 "Cmts.User" user "User.Comments")
		(21 "Eco1.User" user "User.Eco1")
		(23 "Eco2.User" user "User.Eco2")
		(25 "Edge.Cuts" user "Board Geometry/Outline")
		(27 "Margin" user)
		(31 "F.CrtYd" user "Package Geometry/Place Bound Top")
		(29 "B.CrtYd" user "Package Geometry/Place Bound Bottom")
		(35 "F.Fab" user "Ref Des/Assembly Top")
		(33 "B.Fab" user "Ref Des/Assembly Bottom")
	)
	(footprint ""
		(layer "F.Cu")
		(at 160.402016 -10.849864 -90)
		(property "Reference" "J41"
			(at -8.65886 -21.78558 0)
			(unlocked yes)
			(layer "F.SilkS")
			(effects
				(font
					(size 0.7874 0.5842)
					(thickness 0.1524)
				)
				(justify left)
			)
		)
		(property "Value" ""
			(at 0 0 270)
			(layer "F.Fab")
			(effects
				(font
					(size 1.27 1.27)
				)
			)
		)
		(duplicate_pad_numbers_are_jumpers no)
		(pad "A41" smd rect
			(at -2.750058 8.945118 180)
			(size 0.381 1.4478)
			(layers "F.Cu" "F.Mask" "F.Paste")
			(net "SMB_HOST_CLK_3V3AUX_SDA_R0")
		)
		(pad "A42" smd rect
			(at -2.750058 9.545066 180)
			(size 0.381 1.4478)
			(layers "F.Cu" "F.Mask" "F.Paste")
			(net "GND")
		)
		(pad "A43" smd rect
			(at -2.750058 14.454886 180)
			(size 0.381 1.4478)
			(layers "F.Cu" "F.Mask" "F.Paste")
			(net "FW_RECOVERY")
		)
		(pad "A44" smd rect
			(at -2.750058 15.055088 180)
			(size 0.381 1.4478)
			(layers "F.Cu" "F.Mask" "F.Paste")
			(net "PWRGD_PS_PWROK_R")
		)
		(pad "A45" smd rect
			(at -2.750058 15.655036 180)
			(size 0.381 1.4478)
			(layers "F.Cu" "F.Mask" "F.Paste")
			(net "TP_STBY_EN")
		)
		(pad "A46" smd rect
			(at -2.750058 16.254984 180)
			(size 0.381 1.4478)
			(layers "F.Cu" "F.Mask" "F.Paste")
			(net "RST_MB_STBY_R_N")
		)
		(pad "A47" smd rect
			(at -2.750058 16.854932 180)
			(size 0.381 1.4478)
			(layers "F.Cu" "F.Mask" "F.Paste")
			(net "SCM_SYS_PWRBTN_R_N")
		)
		(pad "A48" smd rect
			(at -2.750058 17.45488 180)
			(size 0.381 1.4478)
			(layers "F.Cu" "F.Mask" "F.Paste")
			(net "SCM_SYS_PWROK_R1")
		)
		(pad "A49" smd rect
			(at -2.750058 18.055082 180)
			(size 0.381 1.4478)
			(layers "F.Cu" "F.Mask" "F.Paste")
			(net "SCM_HDT_DBREQ_N")
		)
		(pad "A50" smd rect
			(at -2.750058 18.65503 180)
			(size 0.381 1.4478)
			(layers "F.Cu" "F.Mask" "F.Paste")
			(net "PU_JTAG_DBP_BMC_PRDY_N")
		)
		(pad "A51" smd rect
			(at -2.750058 19.254978 180)
			(size 0.381 1.4478)
			(layers "F.Cu" "F.Mask" "F.Paste")
			(net "FM_RST_PERST_SCM_N")
		)
		(pad "A52" smd rect
			(at -2.750058 19.854926 180)
			(size 0.381 1.4478)
			(layers "F.Cu" "F.Mask" "F.Paste")
			(net "FM_UARTSW_MSB_R")
		)
		(pad "A53" smd rect
			(at -2.750058 20.455128 180)
			(size 0.381 1.4478)
			(layers "F.Cu" "F.Mask" "F.Paste")
			(net "SCM_ROT_CPU_RST_N")
		)
		(pad "A54" smd rect
			(at -2.750058 21.055076 180)
			(size 0.381 1.4478)
			(layers "F.Cu" "F.Mask" "F.Paste")
			(net "TP_CHASI")
		)
		(pad "A55" smd rect
			(at -2.750058 21.655024 180)
			(size 0.381 1.4478)
			(layers "F.Cu" "F.Mask" "F.Paste")
			(net "FM_UARTSW_LSB_R")
		)
		(pad "A56" smd rect
			(at -2.750058 22.254972 180)
			(size 0.381 1.4478)
			(layers "F.Cu" "F.Mask" "F.Paste")
			(net "IRQ0_A56")
		)
		(pad "A57" smd rect
			(at -2.750058 22.85492 180)
			(size 0.381 1.4478)
			(layers "F.Cu" "F.Mask" "F.Paste")
			(net "FM_SCM_PRSNT1_N")
		)
		(pad "A58" smd rect
			(at -2.750058 23.455122 180)
			(size 0.381 1.4478)
			(layers "F.Cu" "F.Mask" "F.Paste")
			(net "GND")
		)
		(pad "A59" smd rect
			(at -2.750058 24.05507 180)
			(size 0.381 1.4478)
			(layers "F.Cu" "F.Mask" "F.Paste")
			(net "USB3_CPU0_BMC_RX_DP")
		)
		(pad "A60" smd rect
			(at -2.750058 24.655018 180)
			(size 0.381 1.4478)
			(layers "F.Cu" "F.Mask" "F.Paste")
			(net "USB3_CPU0_BMC_RX_DN")
		)
		(pad "A61" smd rect
			(at -2.750058 25.254966 180)
			(size 0.381 1.4478)
			(layers "F.Cu" "F.Mask" "F.Paste")
			(net "GND")
		)
		(pad "A62" smd rect
			(at -2.750058 25.854914 180)
			(size 0.381 1.4478)
			(layers "F.Cu" "F.Mask" "F.Paste")
			(net "TP_PCIE_RXP<1>")
		)
		(pad "A63" smd rect
			(at -2.750058 26.455116 180)
			(size 0.381 1.4478)
			(layers "F.Cu" "F.Mask" "F.Paste")
			(net "TP_PCIE_RXN<1>")
		)
		(pad "A64" smd rect
			(at -2.750058 27.055064 180)
			(size 0.381 1.4478)
			(layers "F.Cu" "F.Mask" "F.Paste")
			(net "GND")
		)
		(pad "A65" smd rect
			(at -2.750058 27.655012 180)
			(size 0.381 1.4478)
			(layers "F.Cu" "F.Mask" "F.Paste")
			(net "P2E_MB_BMC_RX_BUF_DP<0>")
		)
		(pad "A66" smd rect
			(at -2.750058 28.25496 180)
			(size 0.381 1.4478)
			(layers "F.Cu" "F.Mask" "F.Paste")
			(net "P2E_MB_BMC_RX_BUF_DN<0>")
		)
		(pad "A67" smd rect
			(at -2.750058 28.854908 180)
			(size 0.381 1.4478)
			(layers "F.Cu" "F.Mask" "F.Paste")
			(net "GND")
		)
		(pad "A68" smd rect
			(at -2.750058 29.45511 180)
			(size 0.381 1.4478)
			(layers "F.Cu" "F.Mask" "F.Paste")
			(net "CLK_100M_BMC_RC_DP")
		)
		(pad "A69" smd rect
			(at -2.750058 30.055058 180)
			(size 0.381 1.4478)
			(layers "F.Cu" "F.Mask" "F.Paste")
			(net "CLK_100M_BMC_RC_DN")
		)
		(pad "A70" smd rect
			(at -2.750058 30.655006 180)
			(size 0.381 1.4478)
			(layers "F.Cu" "F.Mask" "F.Paste")
			(net "GND")
		)
		(pad "B1" smd rect
			(at -5.700014 -18.465038 180)
			(size 0.381 1.4478)
			(layers "F.Cu" "F.Mask" "F.Paste")
			(net "CLK_ESPI_CPU0_CLK1")
		)
		(pad "B2" smd rect
			(at -5.700014 -17.86509 180)
			(size 0.381 1.4478)
			(layers "F.Cu" "F.Mask" "F.Paste")
			(net "ESPI_CPU0_CS1_N")
		)
		(pad "B3" smd rect
			(at -5.700014 -17.264888 180)
			(size 0.381 1.4478)
			(layers "F.Cu" "F.Mask" "F.Paste")
			(net "ESPI_CPU0_ALERT_N")
		)
		(pad "B4" smd rect
			(at -5.700014 -16.66494 180)
			(size 0.381 1.4478)
			(layers "F.Cu" "F.Mask" "F.Paste")
			(net "RST_ESPI_CPU0_RSTOUT_N")
		)
		(pad "B5" smd rect
			(at -5.700014 -16.064992 180)
			(size 0.381 1.4478)
			(layers "F.Cu" "F.Mask" "F.Paste")
			(net "ESPI_CPU0_D0")
		)
		(pad "B6" smd rect
			(at -5.700014 -15.465044 180)
			(size 0.381 1.4478)
			(layers "F.Cu" "F.Mask" "F.Paste")
			(net "ESPI_CPU0_D1")
		)
		(pad "B7" smd rect
			(at -5.700014 -14.865096 180)
			(size 0.381 1.4478)
			(layers "F.Cu" "F.Mask" "F.Paste")
			(net "ESPI_CPU0_D2")
		)
		(pad "B8" smd rect
			(at -5.700014 -14.264894 180)
			(size 0.381 1.4478)
			(layers "F.Cu" "F.Mask" "F.Paste")
			(net "ESPI_CPU0_D3")
		)
		(pad "B9" smd rect
			(at -5.700014 -13.664946 180)
			(size 0.381 1.4478)
			(layers "F.Cu" "F.Mask" "F.Paste")
			(net "FM_LPC_ESPI_SEL")
		)
		(pad "B10" smd rect
			(at -5.700014 -13.064998 180)
			(size 0.381 1.4478)
			(layers "F.Cu" "F.Mask" "F.Paste")
			(net "GND")
		)
		(pad "B11" smd rect
			(at -5.700014 -12.46505 180)
			(size 0.381 1.4478)
			(layers "F.Cu" "F.Mask" "F.Paste")
			(net "SPI_CPU0_LVC3_SCM_CLK")
		)
		(pad "B12" smd rect
			(at -5.700014 -11.865102 180)
			(size 0.381 1.4478)
			(layers "F.Cu" "F.Mask" "F.Paste")
			(net "SPI_CPU0_LVC3_SCM_CS0_N")
		)
		(pad "B13" smd rect
			(at -5.700014 -11.2649 180)
			(size 0.381 1.4478)
			(layers "F.Cu" "F.Mask" "F.Paste")
			(net "SPI_CPU0_LVC3_SCM_D0")
		)
		(pad "B14" smd rect
			(at -5.700014 -10.664952 180)
			(size 0.381 1.4478)
			(layers "F.Cu" "F.Mask" "F.Paste")
			(net "SPI_CPU0_LVC3_SCM_D1")
		)
		(pad "B15" smd rect
			(at -5.700014 -10.065004 180)
			(size 0.381 1.4478)
			(layers "F.Cu" "F.Mask" "F.Paste")
			(net "SPI_CPU0_LVC3_SCM_D2")
		)
	)
)
